(kicad_pcb
	(version 20240108)
	(generator "pcbnew")
	(generator_version "8.0")
	(general
		(thickness 1.586)
		(legacy_teardrops no)
	)
	(paper "A4")
	(title_block
		(title "GMSL Serializer")
		(date "2024-11-27")
		(rev "1.1.1")
		(company "Antmicro Ltd")
		(comment 1 "www.antmicro.com")
		(comment 9 "footprints 15-19 of 117")
	)
	(layers
		(0 "F.Cu" signal)
		(1 "In1.Cu" power)
		(2 "In2.Cu" power)
		(31 "B.Cu" signal)
		(32 "B.Adhes" user "B.Adhesive")
		(33 "F.Adhes" user "F.Adhesive")
		(34 "B.Paste" user)
		(35 "F.Paste" user)
		(36 "B.SilkS" user "B.Silkscreen")
		(37 "F.SilkS" user "F.Silkscreen")
		(38 "B.Mask" user)
		(39 "F.Mask" user)
		(40 "Dwgs.User" user "User.Drawings")
		(41 "Cmts.User" user "User.Comments")
		(42 "Eco1.User" user "User.Eco1")
		(43 "Eco2.User" user "User.Eco2")
		(44 "Edge.Cuts" user)
		(45 "Margin" user)
		(46 "B.CrtYd" user "B.Courtyard")
		(47 "F.CrtYd" user "F.Courtyard")
		(48 "B.Fab" user)
		(49 "F.Fab" user)
	)
	(footprint "antmicro-footprints:R_0402_1005Metric"
		(layer "F.Cu")
		(at 152.908 100.584 -135)
		(descr "Resistor SMD 0402")
		(tags "resistor SMD 0402")
		(property "Reference" "R20"
			(at -0.895197 -0.408708 45)
			(layer "F.SilkS")
			(effects
				(font
					(size 0.7 0.7)
					(thickness 0.15)
				)
				(justify left bottom)
			)
		)
		(property "Value" "R_0R_0402"
			(at -1.011843 1.772046 45)
			(layer "F.Fab")
			(effects
				(font
					(size 0.7 0.7)
					(thickness 0.15)
				)
				(justify right bottom)
			)
		)
		(property "Footprint" "antmicro-footprints:R_0402_1005Metric"
			(at 0 0 -135)
			(layer "F.Fab")
			(hide yes)
			(effects
				(font
					(size 1.27 1.27)
					(thickness 0.15)
				)
			)
		)
		(property "Datasheet" "https://industrial.panasonic.com/cdbs/www-data/pdf/RDA0000/AOA0000C301.pdf"
			(at 0 0 -135)
			(layer "F.Fab")
			(hide yes)
			(effects
				(font
					(size 1.27 1.27)
					(thickness 0.15)
				)
			)
		)
		(property "Author" "Antmicro"
			(at 189.906655 279.829912 0)
			(layer "F.Fab")
			(hide yes)
			(effects
				(font
					(size 1 1)
					(thickness 0.15)
				)
			)
		)
		(property "Current" "1A"
			(at 189.906655 279.829912 0)
			(layer "F.Fab")
			(hide yes)
			(effects
				(font
					(size 1 1)
					(thickness 0.15)
				)
			)
		)
		(property "License" "Apache-2.0"
			(at 189.906655 279.829912 0)
			(layer "F.Fab")
			(hide yes)
			(effects
				(font
					(size 1 1)
					(thickness 0.15)
				)
			)
		)
		(property "MPN" "ERJ2GE0R00X"
			(at 189.906655 279.829912 0)
			(layer "F.Fab")
			(hide yes)
			(effects
				(font
					(size 1 1)
					(thickness 0.15)
				)
			)
		)
		(property "Manufacturer" "Panasonic"
			(at 189.906655 279.829912 0)
			(layer "F.Fab")
			(hide yes)
			(effects
				(font
					(size 1 1)
					(thickness 0.15)
				)
			)
		)
		(property "Tolerance" ""
			(at 189.906655 279.829912 0)
			(layer "F.Fab")
			(hide yes)
			(effects
				(font
					(size 1 1)
					(thickness 0.15)
				)
			)
		)
		(property "Val" "0R"
			(at 189.906655 279.829912 0)
			(layer "F.Fab")
			(hide yes)
			(effects
				(font
					(size 1 1)
					(thickness 0.15)
				)
			)
		)
		(sheetname "Serializer")
		(sheetfile "serializer.kicad_sch")
		(attr smd)
		(fp_poly
			(pts
				(xy -0.925 -0.47) (xy 0.925 -0.47) (xy 0.925 0.47) (xy -0.925 0.47)
			)
			(stroke
				(width 0.05)
				(type default)
			)
			(fill none)
			(layer "F.CrtYd")
		)
		(fp_poly
			(pts
				(xy -0.5 -0.25) (xy 0.5 -0.25) (xy 0.5 0.25) (xy -0.5 0.25)
			)
			(stroke
				(width 0.15)
				(type solid)
			)
			(fill none)
			(layer "F.Fab")
		)
		(fp_text user "${REFERENCE}"
			(at -0.95 3.168 45)
			(layer "F.Fab")
			(hide yes)
			(effects
				(font
					(size 0.7 0.7)
					(thickness 0.15)
				)
				(justify right bottom)
			)
		)
		(fp_text user "License: Apache-2.0"
			(at -0.949999 5.169 45)
			(layer "F.Fab")
			(hide yes)
			(effects
				(font
					(size 0.7 0.7)
					(thickness 0.15)
				)
				(justify right bottom)
			)
		)
		(fp_text user "Author: Antmicro"
			(at -0.95 4.169 45)
			(layer "F.Fab")
			(hide yes)
			(effects
				(font
					(size 0.7 0.7)
					(thickness 0.15)
				)
				(justify right bottom)
			)
		)
		(pad "1" smd roundrect
			(at -0.48 0 225)
			(size 0.59 0.64)
			(layers "F.Cu" "F.Paste" "F.Mask")
			(roundrect_rratio 0.25)
			(net 14 "/Serializer/X2_R")
			(pintype "passive")
		)
		(pad "2" smd roundrect
			(at 0.48 0 225)
			(size 0.59 0.64)
			(layers "F.Cu" "F.Paste" "F.Mask")
			(roundrect_rratio 0.25)
			(net 67 "/Serializer/X2")
			(pintype "passive")
		)
	)
	(footprint "antmicro-footprints:R_0402_1005Metric"
		(layer "F.Cu")
		(at 136.855 79.675 -90)
		(descr "Resistor SMD 0402")
		(tags "resistor SMD 0402")
		(property "Reference" "R7"
			(at -0.935 -1.365 90)
			(layer "F.SilkS")
			(effects
				(font
					(size 0.7 0.7)
					(thickness 0.15)
				)
				(justify right bottom)
			)
		)
		(property "Value" "R_10k_0402"
			(at -1.011843 1.772047 90)
			(layer "F.Fab")
			(effects
				(font
					(size 0.7 0.7)
					(thickness 0.15)
				)
				(justify right bottom)
			)
		)
		(property "Footprint" "antmicro-footprints:R_0402_1005Metric"
			(at 0 0 -90)
			(layer "F.Fab")
			(hide yes)
			(effects
				(font
					(size 1.27 1.27)
					(thickness 0.15)
				)
			)
		)
		(property "Datasheet" "https://www.bourns.com/docs/product-datasheets/cr.pdf"
			(at 0 0 -90)
			(layer "F.Fab")
			(hide yes)
			(effects
				(font
					(size 1.27 1.27)
					(thickness 0.15)
				)
			)
		)
		(property "Author" "Antmicro"
			(at 59.1 218.15 0)
			(layer "F.Fab")
			(hide yes)
			(effects
				(font
					(size 1 1)
					(thickness 0.15)
				)
			)
		)
		(property "License" "Apache-2.0"
			(at 59.1 218.15 0)
			(layer "F.Fab")
			(hide yes)
			(effects
				(font
					(size 1 1)
					(thickness 0.15)
				)
			)
		)
		(property "MPN" "CR0402-FX-1002GLF"
			(at 59.1 218.15 0)
			(layer "F.Fab")
			(hide yes)
			(effects
				(font
					(size 1 1)
					(thickness 0.15)
				)
			)
		)
		(property "Manufacturer" "Bourns"
			(at 59.1 218.15 0)
			(layer "F.Fab")
			(hide yes)
			(effects
				(font
					(size 1 1)
					(thickness 0.15)
				)
			)
		)
		(property "Tolerance" "1%"
			(at 59.1 218.15 0)
			(layer "F.Fab")
			(hide yes)
			(effects
				(font
					(size 1 1)
					(thickness 0.15)
				)
			)
		)
		(property "Val" "10k"
			(at 59.1 218.15 0)
			(layer "F.Fab")
			(hide yes)
			(effects
				(font
					(size 1 1)
					(thickness 0.15)
				)
			)
		)
		(sheetname "Supply")
		(sheetfile "supply.kicad_sch")
		(attr smd)
		(fp_rect
			(start -0.925 -0.47)
			(end 0.925 0.47)
			(stroke
				(width 0.05)
				(type default)
			)
			(fill none)
			(layer "F.CrtYd")
		)
		(fp_rect
			(start -0.5 -0.25)
			(end 0.5 0.25)
			(stroke
				(width 0.15)
				(type solid)
			)
			(fill none)
			(layer "F.Fab")
		)
		(fp_text user "${REFERENCE}"
			(at -0.95 3.168 90)
			(layer "F.Fab")
			(hide yes)
			(effects
				(font
					(size 0.7 0.7)
					(thickness 0.15)
				)
				(justify right bottom)
			)
		)
		(fp_text user "License: Apache-2.0"
			(at -0.95 5.169 90)
			(layer "F.Fab")
			(hide yes)
			(effects
				(font
					(size 0.7 0.7)
					(thickness 0.15)
				)
				(justify right bottom)
			)
		)
		(fp_text user "Author: Antmicro"
			(at -0.95 4.169 90)
			(layer "F.Fab")
			(hide yes)
			(effects
				(font
					(size 0.7 0.7)
					(thickness 0.15)
				)
				(justify right bottom)
			)
		)
		(pad "1" smd roundrect
			(at -0.48 0 270)
			(size 0.59 0.64)
			(layers "F.Cu" "F.Paste" "F.Mask")
			(roundrect_rratio 0.25)
			(net 62 "/Supply/EN_5V")
			(pintype "passive")
		)
		(pad "2" smd roundrect
			(at 0.48 0 270)
			(size 0.59 0.64)
			(layers "F.Cu" "F.Paste" "F.Mask")
			(roundrect_rratio 0.25)
			(net 2 "+12V")
			(pintype "passive")
		)
	)
	(footprint "antmicro-footprints:R_0402_1005Metric"
		(layer "F.Cu")
		(at 133.1 105.574)
		(descr "Resistor SMD 0402")
		(tags "resistor SMD 0402")
		(property "Reference" "R1"
			(at 1.05 -4.890664 0)
			(layer "F.SilkS")
			(effects
				(font
					(size 0.7 0.7)
					(thickness 0.15)
				)
				(justify left bottom)
			)
		)
		(property "Value" "R_10k_0402"
			(at -1.011843 1.772047 0)
			(layer "F.Fab")
			(effects
				(font
					(size 0.7 0.7)
					(thickness 0.15)
				)
				(justify left bottom)
			)
		)
		(property "Footprint" "antmicro-footprints:R_0402_1005Metric"
			(at 0 0 0)
			(layer "F.Fab")
			(hide yes)
			(effects
				(font
					(size 1.27 1.27)
					(thickness 0.15)
				)
			)
		)
		(property "Datasheet" "https://www.bourns.com/docs/product-datasheets/cr.pdf"
			(at 0 0 0)
			(layer "F.Fab")
			(hide yes)
			(effects
				(font
					(size 1.27 1.27)
					(thickness 0.15)
				)
			)
		)
		(property "Author" "Antmicro"
			(at 0 0 0)
			(layer "F.Fab")
			(hide yes)
			(effects
				(font
					(size 1 1)
					(thickness 0.15)
				)
			)
		)
		(property "License" "Apache-2.0"
			(at 0 0 0)
			(layer "F.Fab")
			(hide yes)
			(effects
				(font
					(size 1 1)
					(thickness 0.15)
				)
			)
		)
		(property "MPN" "CR0402-FX-1002GLF"
			(at 0 0 0)
			(layer "F.Fab")
			(hide yes)
			(effects
				(font
					(size 1 1)
					(thickness 0.15)
				)
			)
		)
		(property "Manufacturer" "Bourns"
			(at 0 0 0)
			(layer "F.Fab")
			(hide yes)
			(effects
				(font
					(size 1 1)
					(thickness 0.15)
				)
			)
		)
		(property "Tolerance" "1%"
			(at 0 0 0)
			(layer "F.Fab")
			(hide yes)
			(effects
				(font
					(size 1 1)
					(thickness 0.15)
				)
			)
		)
		(property "Val" "10k"
			(at 0 0 0)
			(layer "F.Fab")
			(hide yes)
			(effects
				(font
					(size 1 1)
					(thickness 0.15)
				)
			)
		)
		(sheetname "CSI Connector")
		(sheetfile "CSI.kicad_sch")
		(attr smd)
		(fp_rect
			(start -0.925 -0.47)
			(end 0.925 0.47)
			(stroke
				(width 0.05)
				(type default)
			)
			(fill none)
			(layer "F.CrtYd")
		)
		(fp_rect
			(start -0.5 -0.25)
			(end 0.5 0.25)
			(stroke
				(width 0.15)
				(type solid)
			)
			(fill none)
			(layer "F.Fab")
		)
		(fp_text user "License: Apache-2.0"
			(at -0.95 5.169 0)
			(layer "F.Fab")
			(hide yes)
			(effects
				(font
					(size 0.7 0.7)
					(thickness 0.15)
				)
				(justify left bottom)
			)
		)
		(fp_text user "Author: Antmicro"
			(at -0.95 4.169 0)
			(layer "F.Fab")
			(hide yes)
			(effects
				(font
					(size 0.7 0.7)
					(thickness 0.15)
				)
				(justify left bottom)
			)
		)
		(fp_text user "${REFERENCE}"
			(at -0.95 3.168 0)
			(layer "F.Fab")
			(hide yes)
			(effects
				(font
					(size 0.7 0.7)
					(thickness 0.15)
				)
				(justify left bottom)
			)
		)
		(pad "1" smd roundrect
			(at -0.48 0)
			(size 0.59 0.64)
			(layers "F.Cu" "F.Paste" "F.Mask")
			(roundrect_rratio 0.25)
			(net 39 "/CSI Connector/GPIO4_1V8")
			(pintype "passive")
		)
		(pad "2" smd roundrect
			(at 0.48 0)
			(size 0.59 0.64)
			(layers "F.Cu" "F.Paste" "F.Mask")
			(roundrect_rratio 0.25)
			(net 87 "/CSI Connector/GPIO4")
			(pintype "passive")
		)
	)
	(footprint "antmicro-footprints:C_0603_1608Metric"
		(layer "F.Cu")
		(at 145.15 82.98 90)
		(descr "Capacitor SMD 0603")
		(tags "capacitor 0603")
		(property "Reference" "C19"
			(at -1.22 0.5 180)
			(layer "F.SilkS")
			(effects
				(font
					(size 0.7 0.7)
					(thickness 0.15)
				)
				(justify left bottom)
			)
		)
		(property "Value" "C_10u_25V_0603"
			(at -1.42757 1.770288 90)
			(layer "F.Fab")
			(effects
				(font
					(size 0.7 0.7)
					(thickness 0.15)
				)
				(justify left bottom)
			)
		)
		(property "Footprint" "antmicro-footprints:C_0603_1608Metric"
			(at 0 0 90)
			(layer "F.Fab")
			(hide yes)
			(effects
				(font
					(size 1.27 1.27)
					(thickness 0.15)
				)
			)
		)
		(property "Datasheet" "https://product.tdk.com/en/search/capacitor/ceramic/mlcc/info?part_no=C1608X5R1E106M080AC"
			(at 0 0 90)
			(layer "F.Fab")
			(hide yes)
			(effects
				(font
					(size 1.27 1.27)
					(thickness 0.15)
				)
			)
		)
		(property "MPN" "C1608X5R1E106M080AC"
			(at 0 0 90)
			(unlocked yes)
			(layer "F.Fab")
			(hide yes)
			(effects
				(font
					(size 1 1)
					(thickness 0.15)
				)
			)
		)
		(property "Manufacturer" "TDK"
			(at 0 0 90)
			(unlocked yes)
			(layer "F.Fab")
			(hide yes)
			(effects
				(font
					(size 1 1)
					(thickness 0.15)
				)
			)
		)
		(property "License" "Apache-2.0"
			(at 0 0 90)
			(unlocked yes)
			(layer "F.Fab")
			(hide yes)
			(effects
				(font
					(size 1 1)
					(thickness 0.15)
				)
			)
		)
		(property "Author" "Antmicro"
			(at 0 0 90)
			(unlocked yes)
			(layer "F.Fab")
			(hide yes)
			(effects
				(font
					(size 1 1)
					(thickness 0.15)
				)
			)
		)
		(property "Val" "10u"
			(at 0 0 90)
			(unlocked yes)
			(layer "F.Fab")
			(hide yes)
			(effects
				(font
					(size 1 1)
					(thickness 0.15)
				)
			)
		)
		(property "Voltage" "25V"
			(at 0 0 90)
			(unlocked yes)
			(layer "F.Fab")
			(hide yes)
			(effects
				(font
					(size 1 1)
					(thickness 0.15)
				)
			)
		)
		(property "Dielectric" ""
			(at 0 0 90)
			(unlocked yes)
			(layer "F.Fab")
			(hide yes)
			(effects
				(font
					(size 1 1)
					(thickness 0.15)
				)
			)
		)
		(sheetname "Supply")
		(sheetfile "supply.kicad_sch")
		(attr smd)
		(fp_line
			(start -0.15 -0.4)
			(end 0.15 -0.4)
			(stroke
				(width 0.15)
				(type solid)
			)
			(layer "F.SilkS")
		)
		(fp_line
			(start -0.15 0.4)
			(end 0.15 0.4)
			(stroke
				(width 0.15)
				(type solid)
			)
			(layer "F.SilkS")
		)
		(fp_rect
			(start -1.25 -0.65)
			(end 1.25 0.65)
			(stroke
				(width 0.05)
				(type solid)
			)
			(fill none)
			(layer "F.CrtYd")
		)
		(fp_rect
			(start -0.8 -0.4)
			(end 0.8 0.4)
			(stroke
				(width 0.15)
				(type solid)
			)
			(fill none)
			(layer "F.Fab")
		)
		(fp_text user "Author: Antmicro"
			(at -1.682 4.894 90)
			(layer "F.Fab")
			(hide yes)
			(effects
				(font
					(size 0.7 0.7)
					(thickness 0.15)
				)
				(justify left bottom)
			)
		)
		(fp_text user "License: Apache-2.0"
			(at -1.682 5.895 90)
			(layer "F.Fab")
			(hide yes)
			(effects
				(font
					(size 0.7 0.7)
					(thickness 0.15)
				)
				(justify left bottom)
			)
		)
		(fp_text user "${REFERENCE}"
			(at -1.682 3.895 90)
			(layer "F.Fab")
			(hide yes)
			(effects
				(font
					(size 0.7 0.7)
					(thickness 0.15)
				)
				(justify left bottom)
			)
		)
		(pad "1" smd roundrect
			(at -0.7 0 90)
			(size 0.8 1)
			(layers "F.Cu" "F.Paste" "F.Mask")
			(roundrect_rratio 0.2)
			(net 1 "GND")
			(pintype "passive")
		)
		(pad "2" smd roundrect
			(at 0.7 0 90)
			(size 0.8 1)
			(layers "F.Cu" "F.Paste" "F.Mask")
			(roundrect_rratio 0.2)
			(net 2 "+12V")
			(pintype "passive")
		)
	)
	(footprint "antmicro-footprints:LED_0603_1608Metric_G"
		(layer "F.Cu")
		(at 144.98 115.76 -90)
		(descr "LED SMD 0603 Green")
		(tags "LED SMD 0603 Green")
		(property "Reference" "D11"
			(at -3.41 0.51 90)
			(layer "F.SilkS")
			(effects
				(font
					(size 0.7 0.7)
					(thickness 0.15)
				)
				(justify right top)
			)
		)
		(property "Value" "LED_G_0603_LTST-C190GKT"
			(at -0.001 1.599 90)
			(layer "F.Fab")
			(effects
				(font
					(size 0.7 0.7)
					(thickness 0.15)
				)
				(justify right top)
			)
		)
		(property "Footprint" "antmicro-footprints:LED_0603_1608Metric_G"
			(at 0 0 90)
			(layer "F.Fab")
			(hide yes)
			(effects
				(font
					(size 1.27 1.27)
					(thickness 0.15)
				)
			)
		)
		(property "Datasheet" "https://media.digikey.com/pdf/Data%20Sheets/Lite-On%20PDFs/LTST-C190GKT.pdf"
			(at 0 0 90)
			(layer "F.Fab")
			(hide yes)
			(effects
				(font
					(size 1.27 1.27)
					(thickness 0.15)
				)
			)
		)
		(property "MPN" "LTST-C190GKT"
			(at 0 0 -90)
			(unlocked yes)
			(layer "F.Fab")
			(hide yes)
			(effects
				(font
					(size 1 1)
					(thickness 0.15)
				)
			)
		)
		(property "Manufacturer" "Lite-On"
			(at 0 0 -90)
			(unlocked yes)
			(layer "F.Fab")
			(hide yes)
			(effects
				(font
					(size 1 1)
					(thickness 0.15)
				)
			)
		)
		(property "Author" "Antmicro"
			(at 0 0 -90)
			(unlocked yes)
			(layer "F.Fab")
			(hide yes)
			(effects
				(font
					(size 1 1)
					(thickness 0.15)
				)
			)
		)
		(property "License" "Apache-2.0"
			(at 0 0 -90)
			(unlocked yes)
			(layer "F.Fab")
			(hide yes)
			(effects
				(font
					(size 1 1)
					(thickness 0.15)
				)
			)
		)
		(property "VSD_class" "LED"
			(at 0 0 -90)
			(unlocked yes)
			(layer "F.Fab")
			(hide yes)
			(effects
				(font
					(size 1 1)
					(thickness 0.15)
				)
			)
		)
		(property "Color" "Green"
			(at 0 0 -90)
			(unlocked yes)
			(layer "F.Fab")
			(hide yes)
			(effects
				(font
					(size 1 1)
					(thickness 0.15)
				)
			)
		)
		(sheetname "Supply")
		(sheetfile "supply.kicad_sch")
		(attr smd)
		(fp_line
			(start 0.22 0.35)
			(end -0.22 0.35)
			(stroke
				(width 0.15)
				(type solid)
			)
			(layer "F.SilkS")
		)
		(fp_line
			(start -0.094672 0.201008)
			(end -0.094672 -0.198992)
			(stroke
				(width 0.1)
				(type solid)
			)
			(layer "F.SilkS")
		)
		(fp_line
			(start 0.105328 0.201008)
			(end -0.094672 0.001008)
			(stroke
				(width 0.1)
				(type solid)
			)
			(layer "F.SilkS")
		)
		(fp_line
			(start 0.105328 0.201008)
			(end 0.105328 -0.198992)
			(stroke
				(width 0.1)
				(type solid)
			)
			(layer "F.SilkS")
		)
		(fp_line
			(start -0.094672 0.001008)
			(end -0.24 0.001008)
			(stroke
				(width 0.1)
				(type solid)
			)
			(layer "F.SilkS")
		)
		(fp_line
			(start -0.094672 0.001008)
			(end 0.105328 -0.198992)
			(stroke
				(width 0.1)
				(type solid)
			)
			(layer "F.SilkS")
		)
		(fp_line
			(start 0.105328 0.001008)
			(end 0.24 0.001)
			(stroke
				(width 0.1)
				(type solid)
			)
			(layer "F.SilkS")
		)
		(fp_line
			(start -1.18 -0.319)
			(end -1.18 0.321)
			(stroke
				(width 0.15)
				(type solid)
			)
			(layer "F.SilkS")
		)
		(fp_line
			(start 0.22 -0.35)
			(end -0.22 -0.35)
			(stroke
				(width 0.15)
				(type solid)
			)
			(layer "F.SilkS")
		)
		(fp_rect
			(start 1.25 0.65)
			(end -1.25 -0.65)
			(stroke
				(width 0.05)
				(type solid)
			)
			(fill none)
			(layer "F.CrtYd")
		)
		(fp_line
			(start -0.199 0.2)
			(end -0.199 0.1)
			(stroke
				(width 0.15)
				(type solid)
			)
			(layer "F.Fab")
		)
		(fp_line
			(start 0.201 0.2)
			(end 0.201 0)
			(stroke
				(width 0.15)
				(type solid)
			)
			(layer "F.Fab")
		)
		(fp_line
			(start -0.199 0)
			(end -0.597 0)
			(stroke
				(width 0.15)
				(type solid)
			)
			(layer "F.Fab")
		)
		(fp_line
			(start -0.101 0)
			(end 0.201 0.2)
			(stroke
				(width 0.15)
				(type solid)
			)
			(layer "F.Fab")
		)
		(fp_line
			(start 0.201 0)
			(end 0.201 -0.202)
			(stroke
				(width 0.15)
				(type solid)
			)
			(layer "F.Fab")
		)
		(fp_line
			(start 0.599 0)
			(end 0.201 0)
			(stroke
				(width 0.15)
				(type solid)
			)
			(layer "F.Fab")
		)
		(fp_line
			(start -0.199 -0.202)
			(end -0.199 0.1)
			(stroke
				(width 0.15)
				(type solid)
			)
			(layer "F.Fab")
		)
		(fp_line
			(start 0.201 -0.202)
			(end -0.101 0)
			(stroke
				(width 0.15)
				(type solid)
			)
			(layer "F.Fab")
		)
		(fp_rect
			(start 0.848 0.4)
			(end -0.85 -0.402)
			(stroke
				(width 0.15)
				(type solid)
			)
			(fill none)
			(layer "F.Fab")
		)
		(fp_text user "License: Apache-2.0"
			(at -1.4224 3.599 90)
			(layer "F.Fab")
			(hide yes)
			(effects
				(font
					(size 0.7 0.7)
					(thickness 0.15)
				)
				(justify right top)
			)
		)
		(fp_text user "${REFERENCE}"
			(at -1.4224 5.999 90)
			(layer "F.Fab")
			(hide yes)
			(effects
				(font
					(size 0.7 0.7)
					(thickness 0.15)
				)
				(justify right top)
			)
		)
		(fp_text user "Author: Antmicro"
			(at -1.4224 4.799 90)
			(layer "F.Fab")
			(hide yes)
			(effects
				(font
					(size 0.7 0.7)
					(thickness 0.15)
				)
				(justify right top)
			)
		)
		(pad "1" smd roundrect
			(at -0.7 0 90)
			(size 0.8 1)
			(layers "F.Cu" "F.Paste" "F.Mask")
			(roundrect_rratio 0.2)
			(net 95 "Net-(D11-C)")
			(pinfunction "C")
			(pintype "passive")
		)
		(pad "2" smd roundrect
			(at 0.7 0 90)
			(size 0.8 1)
			(layers "F.Cu" "F.Paste" "F.Mask")
			(roundrect_rratio 0.2)
			(net 10 "+3V3")
			(pinfunction "A")
			(pintype "passive")
		)
	)
)
